(kicad_pcb
	(version 20241229)
	(generator "pcbnew")
	(generator_version "9.0")
	(general
		(thickness 1.711)
		(legacy_teardrops no)
	)
	(paper "A4")
	(title_block
		(title "Antmicro Baseboard for Jetson AGX Thor")
		(date "2026-02-18")
		(rev "1.1.0")
		(company "Antmicro Ltd")
		(comment 1 "www.antmicro.com")
		(comment 9 "footprints 947-951 of 1170")
	)
	(layers
		(0 "F.Cu" signal)
		(4 "In1.Cu" signal)
		(6 "In2.Cu" signal)
		(8 "In3.Cu" signal)
		(10 "In4.Cu" jumper)
		(12 "In5.Cu" signal)
		(14 "In6.Cu" signal)
		(16 "In7.Cu" signal)
		(18 "In8.Cu" signal)
		(2 "B.Cu" signal)
		(9 "F.Adhes" user "F.Adhesive")
		(11 "B.Adhes" user "B.Adhesive")
		(13 "F.Paste" user)
		(15 "B.Paste" user)
		(5 "F.SilkS" user "F.Silkscreen")
		(7 "B.SilkS" user "B.Silkscreen")
		(1 "F.Mask" user)
		(3 "B.Mask" user)
		(17 "Dwgs.User" user "User.Drawings")
		(19 "Cmts.User" user "User.Comments")
		(21 "Eco1.User" user "User.Eco1")
		(23 "Eco2.User" user "User.Eco2")
		(25 "Edge.Cuts" user)
		(27 "Margin" user)
		(31 "F.CrtYd" user "F.Courtyard")
		(29 "B.CrtYd" user "B.Courtyard")
		(35 "F.Fab" user)
		(33 "B.Fab" user)
	)
	(footprint "antmicro-footprints:R_0402_1005Metric"
		(layer "B.Cu")
		(at 161.8 57.5 -90)
		(descr "Resistor SMD 0402")
		(tags "resistor SMD 0402")
		(property "Reference" "R240"
			(at -1.7 0.5 90)
			(layer "B.SilkS")
			(effects
				(font
					(size 0.7 0.7)
					(thickness 0.15)
				)
				(justify left bottom mirror)
			)
		)
		(property "Value" "R_470R_0402"
			(at -1.011843 -1.772046 90)
			(layer "B.Fab")
			(effects
				(font
					(size 0.7 0.7)
					(thickness 0.15)
				)
				(justify left bottom mirror)
			)
		)
		(property "Datasheet" "https://www.bourns.com/docs/product-datasheets/cr.pdf"
			(at 0 0 90)
			(layer "B.Fab")
			(hide yes)
			(effects
				(font
					(size 1.27 1.27)
					(thickness 0.15)
				)
				(justify mirror)
			)
		)
		(property "Description" "SMD Chip Resistor, 470 ohm, ± 1%, 62.5 mW, 0402 [1005 Metric], Thick Film, General Purpose"
			(at 0 0 90)
			(layer "B.Fab")
			(hide yes)
			(effects
				(font
					(size 1.27 1.27)
					(thickness 0.15)
				)
				(justify mirror)
			)
		)
		(property "MPN" "CR0402-FX-4700GLF"
			(at 0 0 90)
			(unlocked yes)
			(layer "B.Fab")
			(hide yes)
			(effects
				(font
					(size 1 1)
					(thickness 0.15)
				)
				(justify mirror)
			)
		)
		(property "Manufacturer" "Bourns"
			(at 0 0 90)
			(unlocked yes)
			(layer "B.Fab")
			(hide yes)
			(effects
				(font
					(size 1 1)
					(thickness 0.15)
				)
				(justify mirror)
			)
		)
		(property "License" "Apache-2.0"
			(at 0 0 90)
			(unlocked yes)
			(layer "B.Fab")
			(hide yes)
			(effects
				(font
					(size 1 1)
					(thickness 0.15)
				)
				(justify mirror)
			)
		)
		(property "Author" "Antmicro"
			(at 0 0 90)
			(unlocked yes)
			(layer "B.Fab")
			(hide yes)
			(effects
				(font
					(size 1 1)
					(thickness 0.15)
				)
				(justify mirror)
			)
		)
		(property "Val" "470R"
			(at 0 0 90)
			(unlocked yes)
			(layer "B.Fab")
			(hide yes)
			(effects
				(font
					(size 1 1)
					(thickness 0.15)
				)
				(justify mirror)
			)
		)
		(property "Tolerance" "1%"
			(at 0 0 90)
			(unlocked yes)
			(layer "B.Fab")
			(hide yes)
			(effects
				(font
					(size 1 1)
					(thickness 0.15)
				)
				(justify mirror)
			)
		)
		(property "Current" "1A"
			(at 0 0 90)
			(unlocked yes)
			(layer "B.Fab")
			(hide yes)
			(effects
				(font
					(size 1 1)
					(thickness 0.15)
				)
				(justify mirror)
			)
		)
		(sheetname "/Power/")
		(sheetfile "power.kicad_sch")
		(attr smd)
		(fp_poly
			(pts
				(xy -0.925 0.47) (xy 0.925 0.47) (xy 0.925 -0.47) (xy -0.925 -0.47)
			)
			(stroke
				(width 0.05)
				(type default)
			)
			(fill no)
			(layer "B.CrtYd")
		)
		(fp_poly
			(pts
				(xy -0.5 0.25) (xy 0.5 0.25) (xy 0.5 -0.25) (xy -0.5 -0.25)
			)
			(stroke
				(width 0.15)
				(type solid)
			)
			(fill no)
			(layer "B.Fab")
		)
		(fp_text user "License: Apache-2.0"
			(at -0.949999 -5.169 90)
			(layer "B.Fab")
			(effects
				(font
					(size 0.7 0.7)
					(thickness 0.15)
				)
				(justify left bottom mirror)
			)
		)
		(fp_text user "Author: Antmicro"
			(at -0.95 -4.169 90)
			(layer "B.Fab")
			(effects
				(font
					(size 0.7 0.7)
					(thickness 0.15)
				)
				(justify left bottom mirror)
			)
		)
		(fp_text user "${REFERENCE}"
			(at -0.95 -3.168 90)
			(layer "B.Fab")
			(effects
				(font
					(size 0.7 0.7)
					(thickness 0.15)
				)
				(justify left bottom mirror)
			)
		)
		(pad "1" smd roundrect
			(at -0.48 0 270)
			(size 0.59 0.64)
			(layers "B.Cu" "B.Mask" "B.Paste")
			(roundrect_rratio 0.25)
			(net 1008 "Net-(D40-A)")
			(pintype "passive")
		)
		(pad "2" smd roundrect
			(at 0.48 0 270)
			(size 0.59 0.64)
			(layers "B.Cu" "B.Mask" "B.Paste")
			(roundrect_rratio 0.25)
			(net 5 "+5V")
			(pintype "passive")
		)
	)
	(footprint "antmicro-footprints:C_0402_1005Metric"
		(layer "B.Cu")
		(at 94 119.78 180)
		(descr "Capacitor SMD 0402")
		(tags "capacitor SMD 0402")
		(property "Reference" "C214"
			(at -3.9 -0.725 0)
			(layer "B.SilkS")
			(effects
				(font
					(size 0.7 0.7)
					(thickness 0.15)
				)
				(justify left bottom mirror)
			)
		)
		(property "Value" "C_220n_0402"
			(at -1.022927 -2.155213 0)
			(layer "B.Fab")
			(effects
				(font
					(size 0.7 0.7)
					(thickness 0.15)
				)
				(justify left bottom mirror)
			)
		)
		(property "Datasheet" "https://www.yageo.com/en/Chart/Download/pdf/CC0402KRX5R6BB224"
			(at 0 0 0)
			(layer "B.Fab")
			(hide yes)
			(effects
				(font
					(size 1.27 1.27)
					(thickness 0.15)
				)
				(justify mirror)
			)
		)
		(property "Description" "SMD Multilayer Ceramic Capacitor, 0.22 µF, 10 V, 0402 [1005 Metric], ± 10%, X5R, CC Series"
			(at 0 0 0)
			(layer "B.Fab")
			(hide yes)
			(effects
				(font
					(size 1.27 1.27)
					(thickness 0.15)
				)
				(justify mirror)
			)
		)
		(property "MPN" "CC0402KRX5R6BB224"
			(at 0 0 180)
			(unlocked yes)
			(layer "B.Fab")
			(hide yes)
			(effects
				(font
					(size 1 1)
					(thickness 0.15)
				)
				(justify mirror)
			)
		)
		(property "Val" "220n"
			(at 0 0 180)
			(unlocked yes)
			(layer "B.Fab")
			(hide yes)
			(effects
				(font
					(size 1 1)
					(thickness 0.15)
				)
				(justify mirror)
			)
		)
		(property "Voltage" "25V"
			(at 0 0 180)
			(unlocked yes)
			(layer "B.Fab")
			(hide yes)
			(effects
				(font
					(size 1 1)
					(thickness 0.15)
				)
				(justify mirror)
			)
		)
		(property "Dielectric" "X7R"
			(at 0 0 180)
			(unlocked yes)
			(layer "B.Fab")
			(hide yes)
			(effects
				(font
					(size 1 1)
					(thickness 0.15)
				)
				(justify mirror)
			)
		)
		(property "Manufacturer" "YAGEO"
			(at 0 0 180)
			(unlocked yes)
			(layer "B.Fab")
			(hide yes)
			(effects
				(font
					(size 1 1)
					(thickness 0.15)
				)
				(justify mirror)
			)
		)
		(property "License" "Apache-2.0"
			(at 0 0 180)
			(unlocked yes)
			(layer "B.Fab")
			(hide yes)
			(effects
				(font
					(size 1 1)
					(thickness 0.15)
				)
				(justify mirror)
			)
		)
		(property "Author" "Antmicro"
			(at 0 0 180)
			(unlocked yes)
			(layer "B.Fab")
			(hide yes)
			(effects
				(font
					(size 1 1)
					(thickness 0.15)
				)
				(justify mirror)
			)
		)
		(property "Public" "False"
			(at 0 0 180)
			(unlocked yes)
			(layer "B.Fab")
			(hide yes)
			(effects
				(font
					(size 1 1)
					(thickness 0.15)
				)
				(justify mirror)
			)
		)
		(sheetname "/Expansion connector/")
		(sheetfile "expansion_connector.kicad_sch")
		(attr smd)
		(fp_rect
			(start -0.925 0.47)
			(end 0.925 -0.47)
			(stroke
				(width 0.05)
				(type default)
			)
			(fill no)
			(layer "B.CrtYd")
		)
		(fp_line
			(start 0.504 0.25)
			(end 0.504 -0.248)
			(stroke
				(width 0.15)
				(type solid)
			)
			(layer "B.Fab")
		)
		(fp_line
			(start 0.504 -0.248)
			(end -0.494 -0.248)
			(stroke
				(width 0.15)
				(type solid)
			)
			(layer "B.Fab")
		)
		(fp_line
			(start -0.494 0.25)
			(end 0.504 0.25)
			(stroke
				(width 0.15)
				(type solid)
			)
			(layer "B.Fab")
		)
		(fp_line
			(start -0.494 -0.248)
			(end -0.494 0.25)
			(stroke
				(width 0.15)
				(type solid)
			)
			(layer "B.Fab")
		)
		(fp_text user "License: Apache-2.0"
			(at -0.939 -5.799 0)
			(layer "B.Fab")
			(effects
				(font
					(size 0.7 0.7)
					(thickness 0.15)
				)
				(justify left bottom mirror)
			)
		)
		(fp_text user "${REFERENCE}"
			(at -0.939 -4.599 0)
			(layer "B.Fab")
			(effects
				(font
					(size 0.7 0.7)
					(thickness 0.15)
				)
				(justify left bottom mirror)
			)
		)
		(fp_text user "Author: Antmicro"
			(at -0.939 -3.399 0)
			(layer "B.Fab")
			(effects
				(font
					(size 0.7 0.7)
					(thickness 0.15)
				)
				(justify left bottom mirror)
			)
		)
		(pad "1" smd roundrect
			(at -0.48 0 180)
			(size 0.59 0.64)
			(layers "B.Cu" "B.Mask" "B.Paste")
			(roundrect_rratio 0.25)
			(net 516 "/Expansion connector/PCIe_{C2x1}.TX0-")
			(pintype "passive")
		)
		(pad "2" smd roundrect
			(at 0.48 0 180)
			(size 0.59 0.64)
			(layers "B.Cu" "B.Mask" "B.Paste")
			(roundrect_rratio 0.25)
			(net 479 "/Expansion connector/PET0_C2_N")
			(pintype "passive")
		)
	)
	(footprint "antmicro-footprints:TP_SMD_0.75mm"
		(layer "B.Cu")
		(at 199.8 122.6 180)
		(property "Reference" "TP2"
			(at 1 1.4 0)
			(layer "B.SilkS")
			(effects
				(font
					(size 0.7 0.7)
					(thickness 0.15)
				)
				(justify right top mirror)
			)
		)
		(property "Value" "TP_0.75mm_SMD"
			(at 0 -1.2 180)
			(layer "B.Fab")
			(effects
				(font
					(size 0.7 0.7)
					(thickness 0.15)
				)
				(justify right top mirror)
			)
		)
		(property "Description" "SMT test point"
			(at 0 0 180)
			(layer "B.Fab")
			(hide yes)
			(effects
				(font
					(size 1.27 1.27)
					(thickness 0.15)
				)
				(justify mirror)
			)
		)
		(property "MPN" ""
			(at 0 0 0)
			(unlocked yes)
			(layer "B.Fab")
			(hide yes)
			(effects
				(font
					(size 1 1)
					(thickness 0.15)
				)
				(justify mirror)
			)
		)
		(property "Manufacturer" ""
			(at 0 0 0)
			(unlocked yes)
			(layer "B.Fab")
			(hide yes)
			(effects
				(font
					(size 1 1)
					(thickness 0.15)
				)
				(justify mirror)
			)
		)
		(property "Author" "Antmicro"
			(at 0 0 0)
			(unlocked yes)
			(layer "B.Fab")
			(hide yes)
			(effects
				(font
					(size 1 1)
					(thickness 0.15)
				)
				(justify mirror)
			)
		)
		(property "License" "Apache-2.0"
			(at 0 0 0)
			(unlocked yes)
			(layer "B.Fab")
			(hide yes)
			(effects
				(font
					(size 1 1)
					(thickness 0.15)
				)
				(justify mirror)
			)
		)
		(sheetname "/USB Hub/")
		(sheetfile "usb_hub.kicad_sch")
		(attr exclude_from_pos_files exclude_from_bom)
		(fp_circle
			(center 0 0)
			(end 0.475 0)
			(stroke
				(width 0.05)
				(type default)
			)
			(fill no)
			(layer "B.CrtYd")
		)
		(fp_text user "Author: Antmicro"
			(at -0.4 -3.901 180)
			(layer "B.Fab")
			(effects
				(font
					(size 0.7 0.7)
					(thickness 0.15)
				)
				(justify right top mirror)
			)
		)
		(fp_text user "${REFERENCE}"
			(at -0.4 -2.7 180)
			(layer "B.Fab")
			(effects
				(font
					(size 0.7 0.7)
					(thickness 0.15)
				)
				(justify right top mirror)
			)
		)
		(fp_text user "License: Apache-2.0"
			(at -0.4 -5.101 180)
			(layer "B.Fab")
			(effects
				(font
					(size 0.7 0.7)
					(thickness 0.15)
				)
				(justify right top mirror)
			)
		)
		(pad "1" smd circle
			(at 0 0 180)
			(size 0.75 0.75)
			(layers "B.Cu" "B.Mask")
			(net 911 "/USB Hub/PRT_CTL2")
			(pinfunction "1")
			(pintype "passive")
		)
	)
	(footprint "antmicro-footprints:C_0402_1005Metric"
		(layer "B.Cu")
		(at 94 122.769999 180)
		(descr "Capacitor SMD 0402")
		(tags "capacitor SMD 0402")
		(property "Reference" "C220"
			(at -3.8 -0.625 0)
			(layer "B.SilkS")
			(effects
				(font
					(size 0.7 0.7)
					(thickness 0.15)
				)
				(justify left bottom mirror)
			)
		)
		(property "Value" "C_220n_0402"
			(at -1.022927 -2.155213 0)
			(layer "B.Fab")
			(effects
				(font
					(size 0.7 0.7)
					(thickness 0.15)
				)
				(justify left bottom mirror)
			)
		)
		(property "Datasheet" "https://www.yageo.com/en/Chart/Download/pdf/CC0402KRX5R6BB224"
			(at 0 0 0)
			(layer "B.Fab")
			(hide yes)
			(effects
				(font
					(size 1.27 1.27)
					(thickness 0.15)
				)
				(justify mirror)
			)
		)
		(property "Description" "SMD Multilayer Ceramic Capacitor, 0.22 µF, 10 V, 0402 [1005 Metric], ± 10%, X5R, CC Series"
			(at 0 0 0)
			(layer "B.Fab")
			(hide yes)
			(effects
				(font
					(size 1.27 1.27)
					(thickness 0.15)
				)
				(justify mirror)
			)
		)
		(property "MPN" "CC0402KRX5R6BB224"
			(at 0 0 180)
			(unlocked yes)
			(layer "B.Fab")
			(hide yes)
			(effects
				(font
					(size 1 1)
					(thickness 0.15)
				)
				(justify mirror)
			)
		)
		(property "Val" "220n"
			(at 0 0 180)
			(unlocked yes)
			(layer "B.Fab")
			(hide yes)
			(effects
				(font
					(size 1 1)
					(thickness 0.15)
				)
				(justify mirror)
			)
		)
		(property "Voltage" "25V"
			(at 0 0 180)
			(unlocked yes)
			(layer "B.Fab")
			(hide yes)
			(effects
				(font
					(size 1 1)
					(thickness 0.15)
				)
				(justify mirror)
			)
		)
		(property "Dielectric" "X7R"
			(at 0 0 180)
			(unlocked yes)
			(layer "B.Fab")
			(hide yes)
			(effects
				(font
					(size 1 1)
					(thickness 0.15)
				)
				(justify mirror)
			)
		)
		(property "Manufacturer" "YAGEO"
			(at 0 0 180)
			(unlocked yes)
			(layer "B.Fab")
			(hide yes)
			(effects
				(font
					(size 1 1)
					(thickness 0.15)
				)
				(justify mirror)
			)
		)
		(property "License" "Apache-2.0"
			(at 0 0 180)
			(unlocked yes)
			(layer "B.Fab")
			(hide yes)
			(effects
				(font
					(size 1 1)
					(thickness 0.15)
				)
				(justify mirror)
			)
		)
		(property "Author" "Antmicro"
			(at 0 0 180)
			(unlocked yes)
			(layer "B.Fab")
			(hide yes)
			(effects
				(font
					(size 1 1)
					(thickness 0.15)
				)
				(justify mirror)
			)
		)
		(property "Public" "False"
			(at 0 0 180)
			(unlocked yes)
			(layer "B.Fab")
			(hide yes)
			(effects
				(font
					(size 1 1)
					(thickness 0.15)
				)
				(justify mirror)
			)
		)
		(sheetname "/Expansion connector/")
		(sheetfile "expansion_connector.kicad_sch")
		(attr smd)
		(fp_poly
			(pts
				(xy -0.925 0.47) (xy 0.925 0.47) (xy 0.925 -0.47) (xy -0.925 -0.47)
			)
			(stroke
				(width 0.05)
				(type default)
			)
			(fill no)
			(layer "B.CrtYd")
		)
		(fp_line
			(start 0.504 0.25)
			(end 0.504 -0.248)
			(stroke
				(width 0.15)
				(type solid)
			)
			(layer "B.Fab")
		)
		(fp_line
			(start 0.504 -0.248)
			(end -0.494 -0.248)
			(stroke
				(width 0.15)
				(type solid)
			)
			(layer "B.Fab")
		)
		(fp_line
			(start -0.494 0.25)
			(end 0.504 0.25)
			(stroke
				(width 0.15)
				(type solid)
			)
			(layer "B.Fab")
		)
		(fp_line
			(start -0.494 -0.248)
			(end -0.494 0.25)
			(stroke
				(width 0.15)
				(type solid)
			)
			(layer "B.Fab")
		)
		(fp_text user "${REFERENCE}"
			(at -0.939 -4.599 0)
			(layer "B.Fab")
			(effects
				(font
					(size 0.7 0.7)
					(thickness 0.15)
				)
				(justify left bottom mirror)
			)
		)
		(fp_text user "License: Apache-2.0"
			(at -0.939 -5.799 0)
			(layer "B.Fab")
			(effects
				(font
					(size 0.7 0.7)
					(thickness 0.15)
				)
				(justify left bottom mirror)
			)
		)
		(fp_text user "Author: Antmicro"
			(at -0.939 -3.399 0)
			(layer "B.Fab")
			(effects
				(font
					(size 0.7 0.7)
					(thickness 0.15)
				)
				(justify left bottom mirror)
			)
		)
		(pad "1" smd roundrect
			(at -0.48 0 180)
			(size 0.59 0.64)
			(layers "B.Cu" "B.Mask" "B.Paste")
			(roundrect_rratio 0.25)
			(net 467 "/Expansion connector/PCIe_{C3x2}.TX1+")
			(pintype "passive")
		)
		(pad "2" smd roundrect
			(at 0.48 0 180)
			(size 0.59 0.64)
			(layers "B.Cu" "B.Mask" "B.Paste")
			(roundrect_rratio 0.25)
			(net 520 "/Expansion connector/PET1_C3_N")
			(pintype "passive")
		)
	)
	(footprint "antmicro-footprints:R_0402_1005Metric"
		(layer "B.Cu")
		(at 109.995 138.43 90)
		(descr "Resistor SMD 0402")
		(tags "resistor SMD 0402")
		(property "Reference" "R221"
			(at -1.35 -2.795 90)
			(layer "B.SilkS")
			(effects
				(font
					(size 0.7 0.7)
					(thickness 0.15)
				)
				(justify right top mirror)
			)
		)
		(property "Value" "R_200R_0402"
			(at -1.011843 -1.772047 90)
			(layer "B.Fab")
			(effects
				(font
					(size 0.7 0.7)
					(thickness 0.15)
				)
				(justify right top mirror)
			)
		)
		(property "Datasheet" "https://www.bourns.com/docs/product-datasheets/cr.pdf"
			(at 0 0 90)
			(layer "B.Fab")
			(hide yes)
			(effects
				(font
					(size 1.27 1.27)
					(thickness 0.15)
				)
				(justify mirror)
			)
		)
		(property "Description" "SMD Chip Resistor, 200 ohm, ± 1%, 62.5 mW, 0402 [1005 Metric], Thick Film, General Purpose"
			(at 0 0 90)
			(layer "B.Fab")
			(hide yes)
			(effects
				(font
					(size 1.27 1.27)
					(thickness 0.15)
				)
				(justify mirror)
			)
		)
		(property "MPN" "CR0402-FX-2000GLF"
			(at 0 0 270)
			(unlocked yes)
			(layer "B.Fab")
			(hide yes)
			(effects
				(font
					(size 1 1)
					(thickness 0.15)
				)
				(justify mirror)
			)
		)
		(property "Manufacturer" "Bourns"
			(at 0 0 270)
			(unlocked yes)
			(layer "B.Fab")
			(hide yes)
			(effects
				(font
					(size 1 1)
					(thickness 0.15)
				)
				(justify mirror)
			)
		)
		(property "License" "Apache-2.0"
			(at 0 0 270)
			(unlocked yes)
			(layer "B.Fab")
			(hide yes)
			(effects
				(font
					(size 1 1)
					(thickness 0.15)
				)
				(justify mirror)
			)
		)
		(property "Author" "Antmicro"
			(at 0 0 270)
			(unlocked yes)
			(layer "B.Fab")
			(hide yes)
			(effects
				(font
					(size 1 1)
					(thickness 0.15)
				)
				(justify mirror)
			)
		)
		(property "Val" "200R"
			(at 0 0 270)
			(unlocked yes)
			(layer "B.Fab")
			(hide yes)
			(effects
				(font
					(size 1 1)
					(thickness 0.15)
				)
				(justify mirror)
			)
		)
		(property "Tolerance" "1%"
			(at 0 0 270)
			(unlocked yes)
			(layer "B.Fab")
			(hide yes)
			(effects
				(font
					(size 1 1)
					(thickness 0.15)
				)
				(justify mirror)
			)
		)
		(sheetname "/M.2/")
		(sheetfile "m2.kicad_sch")
		(attr smd)
		(fp_rect
			(start -0.925 0.47)
			(end 0.925 -0.47)
			(stroke
				(width 0.05)
				(type default)
			)
			(fill no)
			(layer "B.CrtYd")
		)
		(fp_rect
			(start -0.5 0.25)
			(end 0.5 -0.25)
			(stroke
				(width 0.15)
				(type solid)
			)
			(fill no)
			(layer "B.Fab")
		)
		(fp_text user "License: Apache-2.0"
			(at -0.95 -5.169 90)
			(layer "B.Fab")
			(effects
				(font
					(size 0.7 0.7)
					(thickness 0.15)
				)
				(justify right top mirror)
			)
		)
		(fp_text user "Author: Antmicro"
			(at -0.95 -4.169 90)
			(layer "B.Fab")
			(effects
				(font
					(size 0.7 0.7)
					(thickness 0.15)
				)
				(justify right top mirror)
			)
		)
		(fp_text user "${REFERENCE}"
			(at -0.95 -3.168 90)
			(layer "B.Fab")
			(effects
				(font
					(size 0.7 0.7)
					(thickness 0.15)
				)
				(justify right top mirror)
			)
		)
		(pad "1" smd roundrect
			(at -0.48 0 90)
			(size 0.59 0.64)
			(layers "B.Cu" "B.Mask" "B.Paste")
			(roundrect_rratio 0.25)
			(net 545 "Net-(D33-A)")
			(pintype "passive")
		)
		(pad "2" smd roundrect
			(at 0.48 0 90)
			(size 0.59 0.64)
			(layers "B.Cu" "B.Mask" "B.Paste")
			(roundrect_rratio 0.25)
			(net 2 "+3V3")
			(pintype "passive")
		)
	)
)
